# T6G (Grand Teton) — schematic netlist excerpt (pin names and nets, part order shuffled) for the footprints in the layout excerpt that follows; sources: Cadence DE-HDL packaged netlist, KiCad conversion of 04192023_DAF0TMB3IC0_F0TG_MB_C_brd_V02_OCP.brd

R736  Q_RES  10K 5% EMPTY  pkg 0402LF  page 76 : A = PVDD18_S5_P1 ; B = PD_ESPI_CPU1_CLK2
R1648  Q_RES  0 5% CHIP  pkg 0402LF  page 174 : A = JTAG_CPU0_R_TDI ; B = JTAG_CPU0_TDI

(kicad_pcb
	(version 20260206)
	(generator "pcbnew")
	(generator_version "10.0")
	(general
		(thickness 1.6)
		(legacy_teardrops no)
	)
	(paper "A4")
	(title_block
		(title "04192023_DAF0TMB3IC0_F0TG_MB_C_brd_V02_OCP.brd")
		(comment 1 "Grand Teton / footprints 4271-4272 of 8354")
	)
	(layers
		(0 "F.Cu" signal "TOP")
		(4 "In1.Cu" signal "GND")
		(6 "In2.Cu" signal "IN1")
		(8 "In3.Cu" signal "GND1")
		(10 "In4.Cu" signal "IN2")
		(12 "In5.Cu" signal "GND2")
		(14 "In6.Cu" signal "IN3")
		(16 "In7.Cu" signal "GND3")
		(18 "In8.Cu" signal "VCC")
		(20 "In9.Cu" signal "VCC1")
		(22 "In10.Cu" signal "GND4")
		(24 "In11.Cu" signal "IN4")
		(26 "In12.Cu" signal "GND5")
		(28 "In13.Cu" signal "IN5")
		(30 "In14.Cu" signal "GND6")
		(32 "In15.Cu" signal "IN6")
		(34 "In16.Cu" signal "GND7")
		(2 "B.Cu" signal "BOTTOM")
		(9 "F.Adhes" user "F.Adhesive")
		(11 "B.Adhes" user "B.Adhesive")
		(13 "F.Paste" user "Package Geometry/Pastemask Top")
		(15 "B.Paste" user "Package Geometry/Pastemask Bottom")
		(5 "F.SilkS" user "Ref Des/Silkscreen Top")
		(7 "B.SilkS" user "Ref Des/Silkscreen Bottom")
		(1 "F.Mask" user "Board Geometry/Soldermask Top")
		(3 "B.Mask" user "Board Geometry/Soldermask Bottom")
		(17 "Dwgs.User" user "User.Drawings")
		(19 "Cmts.User" user "User.Comments")
		(21 "Eco1.User" user "User.Eco1")
		(23 "Eco2.User" user "User.Eco2")
		(25 "Edge.Cuts" user "Board Geometry/Outline")
		(27 "Margin" user)
		(31 "F.CrtYd" user "Package Geometry/Place Bound Top")
		(29 "B.CrtYd" user "Package Geometry/Place Bound Bottom")
		(35 "F.Fab" user "Ref Des/Assembly Top")
		(33 "B.Fab" user "Ref Des/Assembly Bottom")
	)
	(footprint ""
		(layer "F.Cu")
		(at 240.421922 -148.6408)
		(property "Reference" "R1648"
			(at 0 0 0)
			(layer "F.SilkS")
			(hide yes)
			(effects
				(font
					(size 1.27 1.27)
				)
			)
		)
		(property "Value" ""
			(at 0 0 0)
			(layer "F.Fab")
			(effects
				(font
					(size 1.27 1.27)
				)
			)
		)
		(duplicate_pad_numbers_are_jumpers no)
		(fp_line
			(start -0.7874 -0.4064)
			(end 0.7874 -0.4064)
			(stroke
				(width 0.1524)
				(type default)
			)
			(layer "F.SilkS")
		)
		(fp_line
			(start -0.7874 0.4064)
			(end -0.7874 -0.4064)
			(stroke
				(width 0.1524)
				(type default)
			)
			(layer "F.SilkS")
		)
		(fp_line
			(start 0.7874 -0.4064)
			(end 0.7874 0.4064)
			(stroke
				(width 0.1524)
				(type default)
			)
			(layer "F.SilkS")
		)
		(fp_line
			(start 0.7874 0.4064)
			(end -0.7874 0.4064)
			(stroke
				(width 0.1524)
				(type default)
			)
			(layer "F.SilkS")
		)
		(fp_line
			(start -0.67945 -0.305054)
			(end -0.12065 -0.305054)
			(stroke
				(width 0.1)
				(type default)
			)
			(layer "F.Fab")
		)
		(fp_line
			(start -0.67945 0.3048)
			(end -0.67945 -0.305054)
			(stroke
				(width 0.1)
				(type default)
			)
			(layer "F.Fab")
		)
		(fp_line
			(start -0.12065 -0.305054)
			(end -0.12065 -0.2794)
			(stroke
				(width 0.1)
				(type default)
			)
			(layer "F.Fab")
		)
		(fp_line
			(start -0.12065 -0.2794)
			(end 0.12065 -0.2794)
			(stroke
				(width 0.1)
				(type default)
			)
			(layer "F.Fab")
		)
		(fp_line
			(start -0.12065 0.2794)
			(end -0.12065 0.3048)
			(stroke
				(width 0.1)
				(type default)
			)
			(layer "F.Fab")
		)
		(fp_line
			(start -0.12065 0.3048)
			(end -0.67945 0.3048)
			(stroke
				(width 0.1)
				(type default)
			)
			(layer "F.Fab")
		)
		(fp_line
			(start 0.120396 0.2794)
			(end -0.12065 0.2794)
			(stroke
				(width 0.1)
				(type default)
			)
			(layer "F.Fab")
		)
		(fp_line
			(start 0.120396 0.3048)
			(end 0.120396 0.2794)
			(stroke
				(width 0.1)
				(type default)
			)
			(layer "F.Fab")
		)
		(fp_line
			(start 0.12065 -0.3048)
			(end 0.67945 -0.3048)
			(stroke
				(width 0.1)
				(type default)
			)
			(layer "F.Fab")
		)
		(fp_line
			(start 0.12065 -0.2794)
			(end 0.12065 -0.3048)
			(stroke
				(width 0.1)
				(type default)
			)
			(layer "F.Fab")
		)
		(fp_line
			(start 0.67945 -0.3048)
			(end 0.67945 0.3048)
			(stroke
				(width 0.1)
				(type default)
			)
			(layer "F.Fab")
		)
		(fp_line
			(start 0.67945 0.3048)
			(end 0.120396 0.3048)
			(stroke
				(width 0.1)
				(type default)
			)
			(layer "F.Fab")
		)
		(pad "1" smd circle
			(at -0.40005 0)
			(size 0 0)
			(layers "F.Cu" "F.Mask" "F.Paste")
			(net "JTAG_CPU0_R_TDI")
		)
		(pad "2" smd circle
			(at 0.40005 0)
			(size 0 0)
			(layers "F.Cu" "F.Mask" "F.Paste")
			(net "JTAG_CPU0_TDI")
		)
	)
	(footprint ""
		(layer "F.Cu")
		(at 152.849834 -324.763892 180)
		(property "Reference" "R736"
			(at 0 0 180)
			(layer "F.SilkS")
			(hide yes)
			(effects
				(font
					(size 1.27 1.27)
				)
			)
		)
		(property "Value" ""
			(at 0 0 180)
			(layer "F.Fab")
			(effects
				(font
					(size 1.27 1.27)
				)
			)
		)
		(duplicate_pad_numbers_are_jumpers no)
		(fp_line
			(start 0.7874 0.4064)
			(end -0.7874 0.4064)
			(stroke
				(width 0.1524)
				(type default)
			)
			(layer "F.SilkS")
		)
		(fp_line
			(start 0.7874 -0.4064)
			(end 0.7874 0.4064)
			(stroke
				(width 0.1524)
				(type default)
			)
			(layer "F.SilkS")
		)
		(fp_line
			(start -0.7874 0.4064)
			(end -0.7874 -0.4064)
			(stroke
				(width 0.1524)
				(type default)
			)
			(layer "F.SilkS")
		)
		(fp_line
			(start -0.7874 -0.4064)
			(end 0.7874 -0.4064)
			(stroke
				(width 0.1524)
				(type default)
			)
			(layer "F.SilkS")
		)
		(fp_line
			(start 0.67945 0.3048)
			(end 0.120396 0.3048)
			(stroke
				(width 0.1)
				(type default)
			)
			(layer "F.Fab")
		)
		(fp_line
			(start 0.67945 -0.3048)
			(end 0.67945 0.3048)
			(stroke
				(width 0.1)
				(type default)
			)
			(layer "F.Fab")
		)
		(fp_line
			(start 0.12065 -0.2794)
			(end 0.12065 -0.3048)
			(stroke
				(width 0.1)
				(type default)
			)
			(layer "F.Fab")
		)
		(fp_line
			(start 0.12065 -0.3048)
			(end 0.67945 -0.3048)
			(stroke
				(width 0.1)
				(type default)
			)
			(layer "F.Fab")
		)
		(fp_line
			(start 0.120396 0.3048)
			(end 0.120396 0.2794)
			(stroke
				(width 0.1)
				(type default)
			)
			(layer "F.Fab")
		)
		(fp_line
			(start 0.120396 0.2794)
			(end -0.12065 0.2794)
			(stroke
				(width 0.1)
				(type default)
			)
			(layer "F.Fab")
		)
		(fp_line
			(start -0.12065 0.3048)
			(end -0.67945 0.3048)
			(stroke
				(width 0.1)
				(type default)
			)
			(layer "F.Fab")
		)
		(fp_line
			(start -0.12065 0.2794)
			(end -0.12065 0.3048)
			(stroke
				(width 0.1)
				(type default)
			)
			(layer "F.Fab")
		)
		(fp_line
			(start -0.12065 -0.2794)
			(end 0.12065 -0.2794)
			(stroke
				(width 0.1)
				(type default)
			)
			(layer "F.Fab")
		)
		(fp_line
			(start -0.12065 -0.305054)
			(end -0.12065 -0.2794)
			(stroke
				(width 0.1)
				(type default)
			)
			(layer "F.Fab")
		)
		(fp_line
			(start -0.67945 0.3048)
			(end -0.67945 -0.305054)
			(stroke
				(width 0.1)
				(type default)
			)
			(layer "F.Fab")
		)
		(fp_line
			(start -0.67945 -0.305054)
			(end -0.12065 -0.305054)
			(stroke
				(width 0.1)
				(type default)
			)
			(layer "F.Fab")
		)
		(pad "1" smd circle
			(at -0.40005 0 180)
			(size 0 0)
			(layers "F.Cu" "F.Mask" "F.Paste")
			(net "PVDD18_S5_P1")
		)
		(pad "2" smd circle
			(at 0.40005 0 180)
			(size 0 0)
			(layers "F.Cu" "F.Mask" "F.Paste")
			(net "PD_ESPI_CPU1_CLK2")
		)
	)
)
